# BASEBOARD_FAB2 (Tioga Pass) — schematic netlist excerpt (pin names and nets, part order shuffled) for the footprints in the layout excerpt that follows; sources: Cadence DE-HDL packaged netlist, KiCad conversion of Wiwynn_Tioga_Pass_MB.brd

J1G2  SCONN288_H44441004  SCONN  pkg PIP  page 79
  \12v\(1)  = P12V_NVDIMM_GHJ
  VSS(93)  = GND
  DQ(4)  = M_H_DQ<5>
  VSS(92)  = GND
  DQ(0)  = M_H_DQ<1>
  VSS(91)  = GND
  DQS9P  = M_H_DQS_DP<9>
  DQS9N  = M_H_DQS_DN<9>
  VSS(90)  = GND
  DQ(6)  = M_H_DQ<7>
  VSS(89)  = GND
  DQ(2)  = M_H_DQ<3>
  VSS(88)  = GND
  DQ(12)  = M_H_DQ<13>
  VSS(87)  = GND
  DQ(8)  = M_H_DQ<9>
  VSS(86)  = GND
  DQS10P  = M_H_DQS_DP<10>
  DQS10N  = M_H_DQS_DN<10>
  VSS(85)  = GND
  DQ(14)  = M_H_DQ<15>
  VSS(84)  = GND
  DQ(10)  = M_H_DQ<11>
  VSS(83)  = GND
  DQ(20)  = M_H_DQ<21>
  VSS(82)  = GND
  DQ(16)  = M_H_DQ<17>
  VSS(81)  = GND
  DQS11P  = M_H_DQS_DP<11>
  DQS11N  = M_H_DQS_DN<11>
  VSS(80)  = GND
  DQ(22)  = M_H_DQ<23>
  VSS(79)  = GND
  DQ(18)  = M_H_DQ<19>
  VSS(78)  = GND
  DQ(28)  = M_H_DQ<29>
  VSS(77)  = GND
  DQ(24)  = M_H_DQ<25>
  VSS(76)  = GND
  DQS12P  = M_H_DQS_DP<12>
  DQS12N  = M_H_DQS_DN<12>
  VSS(75)  = GND
  DQ(30)  = M_H_DQ<31>
  VSS(74)  = GND
  DQ(26)  = M_H_DQ<27>
  VSS(73)  = GND
  CB(4)  = M_H_ECC<5>
  VSS(72)  = GND
  CB(0)  = M_H_ECC<1>
  VSS(71)  = GND
  DQS17P  = M_H_DQS_DP<17>
  DQS17N  = M_H_DQS_DN<17>
  VSS(70)  = GND
  CB(6)  = M_H_ECC<7>
  VSS(69)  = GND
  CB(2)  = M_H_ECC<3>
  VSS(68)  = GND
  RESET_N  = M_GHJ_RST_N
  VDD(25)  = PVDDQ_GHJ
  CKE(0)  = M_H_CKE<0>
  VDD(24)  = PVDDQ_GHJ
  ACT_N  = M_H_ACT_N
  BG(0)  = M_H_BG<0>
  VDD(23)  = PVDDQ_GHJ
  A12  = M_H_MA<12>
  A9  = M_H_MA<9>
  VDD(22)  = PVDDQ_GHJ
  A8  = M_H_MA<8>
  A6  = M_H_MA<6>
  VDD(21)  = PVDDQ_GHJ
  A3  = M_H_MA<3>
  A1  = M_H_MA<1>
  VDD(20)  = PVDDQ_GHJ
  CK0P  = M_H_CLK_DP<0>
  CK0N  = M_H_CLK_DN<0>
  VDD(19)  = PVDDQ_GHJ
  VTT(1)  = PVTT_GHJ
  EVENT_N  = FM_DIMM_EVENT_COD_N
  A0  = M_H_MA<0>
  VDD(18)  = PVDDQ_GHJ
  BA(0)  = M_H_BA<0>
  A16_RAS_N  = M_H_MA<16>
  VDD(17)  = PVDDQ_GHJ
  S0_N  = M_H_CS_N<0>
  VDD(16)  = PVDDQ_GHJ
  A15_CAS_N  = M_H_MA<15>
  ODT(0)  = M_H_ODT<0>
  VDD(15)  = PVDDQ_GHJ
  S1_N  = M_H_CS_N<1>
  VDD(14)  = PVDDQ_GHJ
  ODT(1)  = M_H_ODT<1>
  VDD(13)  = PVDDQ_GHJ
  S2_N_C(0)  = M_H_CS_N<2>
  VSS(67)  = GND
  DQ(36)  = M_H_DQ<37>
  VSS(66)  = GND
  DQ(32)  = M_H_DQ<33>
  VSS(65)  = GND
  DQS13P  = M_H_DQS_DP<13>
  DQS13N  = M_H_DQS_DN<13>
  VSS(64)  = GND
  DQ(38)  = M_H_DQ<39>
  VSS(63)  = GND
  DQ(34)  = M_H_DQ<35>
  VSS(62)  = GND
  DQ(44)  = M_H_DQ<45>
  VSS(61)  = GND
  DQ(40)  = M_H_DQ<41>
  VSS(60)  = GND
  DQS14P  = M_H_DQS_DP<14>
  DQS14N  = M_H_DQS_DN<14>
  VSS(59)  = GND
  DQ(46)  = M_H_DQ<47>
  VSS(58)  = GND
  DQ(42)  = M_H_DQ<43>
  VSS(57)  = GND
  DQ(52)  = M_H_DQ<53>
  VSS(56)  = GND
  DQ(48)  = M_H_DQ<49>
  VSS(55)  = GND
  DQS15P  = M_H_DQS_DP<15>
  DQS15N  = M_H_DQS_DN<15>
  VSS(54)  = GND
  DQ(54)  = M_H_DQ<55>
  VSS(53)  = GND
  DQ(50)  = M_H_DQ<51>
  VSS(52)  = GND
  DQ(60)  = M_H_DQ<61>
  VSS(51)  = GND
  DQ(56)  = M_H_DQ<57>
  VSS(50)  = GND
  DQS16P  = M_H_DQS_DP<16>
  DQS16N  = M_H_DQS_DN<16>
  VSS(49)  = GND
  DQ(62)  = M_H_DQ<63>
  VSS(48)  = GND
  DQ(58)  = M_H_DQ<59>
  VSS(47)  = GND
  SA(0)  = GND
  SA(1)  = PVPP_GHJ
  SCL  = SMB_DDR_GHJ_VPP_SCL
  VPP(4)  = PVPP_GHJ
  VPP(3)  = PVPP_GHJ
  RFU(2)  = TP_CH_H_DIMM_H0_RFU_2
  \12v\(0)  = P12V_NVDIMM_GHJ
  VREFCA  = M_H_VREF
  VSS(46)  = GND
  DQ(5)  = M_H_DQ<4>
  VSS(45)  = GND
  DQ(1)  = M_H_DQ<0>
  VSS(44)  = GND
  DQS0N  = M_H_DQS_DN<0>
  DQS0P  = M_H_DQS_DP<0>
  VSS(43)  = GND
  DQ(7)  = M_H_DQ<6>
  VSS(42)  = GND
  DQ(3)  = M_H_DQ<2>
  VSS(41)  = GND
  DQ(13)  = M_H_DQ<12>
  VSS(40)  = GND
  DQ(9)  = M_H_DQ<8>
  VSS(39)  = GND
  DQS1N  = M_H_DQS_DN<1>
  DQS1P  = M_H_DQS_DP<1>
  VSS(38)  = GND
  DQ(15)  = M_H_DQ<14>
  VSS(37)  = GND
  DQ(11)  = M_H_DQ<10>
  VSS(36)  = GND
  DQ(21)  = M_H_DQ<20>
  VSS(35)  = GND
  DQ(17)  = M_H_DQ<16>
  VSS(34)  = GND
  DQS2N  = M_H_DQS_DN<2>
  DQS2P  = M_H_DQS_DP<2>
  VSS(33)  = GND
  DQ(23)  = M_H_DQ<22>
  VSS(32)  = GND
  DQ(19)  = M_H_DQ<18>
  VSS(31)  = GND
  DQ(29)  = M_H_DQ<28>
  VSS(30)  = GND
  DQ(25)  = M_H_DQ<24>
  VSS(29)  = GND
  DQS3N  = M_H_DQS_DN<3>
  DQS3P  = M_H_DQS_DP<3>
  VSS(28)  = GND
  DQ(31)  = M_H_DQ<30>
  VSS(27)  = GND
  DQ(27)  = M_H_DQ<26>
  VSS(26)  = GND
  CB(5)  = M_H_ECC<4>
  VSS(25)  = GND
  CB(1)  = M_H_ECC<0>
  VSS(24)  = GND
  DQS8N  = M_H_DQS_DN<8>
  DQS8P  = M_H_DQS_DP<8>
  VSS(23)  = GND
  CB(7)  = M_H_ECC<6>
  VSS(22)  = GND
  CB(3)  = M_H_ECC<2>
  VSS(21)  = GND
  CKE(1)  = M_H_CKE<1>
  VDD(12)  = PVDDQ_GHJ
  RFU(0)  = TP_CH_H_DIMM_H0_RFU_0
  VDD(11)  = PVDDQ_GHJ
  BG(1)  = M_H_BG<1>
  ALERT_N  = M_H_ALERT_N
  VDD(10)  = PVDDQ_GHJ
  A11  = M_H_MA<11>
  A7  = M_H_MA<7>
  VDD(9)  = PVDDQ_GHJ
  A5  = M_H_MA<5>
  A4  = M_H_MA<4>
  VDD(8)  = PVDDQ_GHJ
  A2  = M_H_MA<2>
  VDD(7)  = PVDDQ_GHJ
  CK1P  = M_H_CLK_DP<1>
  CK1N  = M_H_CLK_DN<1>
  VDD(6)  = PVDDQ_GHJ
  VTT(0)  = PVTT_GHJ
  PAR  = M_H_PAR
  VDD(5)  = PVDDQ_GHJ
  BA(1)  = M_H_BA<1>
  A10  = M_H_MA<10>
  VDD(4)  = PVDDQ_GHJ
  RFU(1)  = TP_CH_H_DIMM_H0_RFU_1
  A14_WE_N  = M_H_MA<14>
  VDD(3)  = PVDDQ_GHJ
  SAVE_N_NC  = FM_ADR_COMPLETE_GHJ_N
  VDD(2)  = PVDDQ_GHJ
  A13  = M_H_MA<13>
  VDD(1)  = PVDDQ_GHJ
  A17  = M_H_MA<17>
  C(2)  = M_H_C<2>
  VDD(0)  = PVDDQ_GHJ
  S3_N_C(1)  = M_H_CS_N<3>
  SA(2)  = GND
  VSS(20)  = GND
  DQ(37)  = M_H_DQ<36>
  VSS(19)  = GND
  DQ(33)  = M_H_DQ<32>
  VSS(18)  = GND
  DQS4N  = M_H_DQS_DN<4>
  DQS4P  = M_H_DQS_DP<4>
  VSS(17)  = GND
  DQ(39)  = M_H_DQ<38>
  VSS(16)  = GND
  DQ(35)  = M_H_DQ<34>
  VSS(15)  = GND
  DQ(45)  = M_H_DQ<44>
  VSS(14)  = GND
  DQ(41)  = M_H_DQ<40>
  VSS(13)  = GND
  DQS5N  = M_H_DQS_DN<5>
  DQS5P  = M_H_DQS_DP<5>
  VSS(12)  = GND
  DQ(47)  = M_H_DQ<46>
  VSS(11)  = GND
  DQ(43)  = M_H_DQ<42>
  VSS(10)  = GND
  DQ(53)  = M_H_DQ<52>
  VSS(9)  = GND
  DQ(49)  = M_H_DQ<48>
  VSS(8)  = GND
  DQS6N  = M_H_DQS_DN<6>
  DQS6P  = M_H_DQS_DP<6>
  VSS(7)  = GND
  DQ(55)  = M_H_DQ<54>
  VSS(6)  = GND
  DQ(51)  = M_H_DQ<50>
  VSS(5)  = GND
  DQ(61)  = M_H_DQ<60>
  VSS(4)  = GND
  DQ(57)  = M_H_DQ<56>
  VSS(3)  = GND
  DQS7N  = M_H_DQS_DN<7>
  DQS7P  = M_H_DQS_DP<7>
  VSS(2)  = GND
  DQ(63)  = M_H_DQ<62>
  VSS(1)  = GND
  DQ(59)  = M_H_DQ<58>
  VSS(0)  = GND
  VDDSPD  = PVPP_GHJ
  SDA  = SMB_DDR_GHJ_VPP_SDA
  VPP(1)  = PVPP_GHJ
  VPP(0)  = PVPP_GHJ
  VPP(2)  = PVPP_GHJ

(kicad_pcb
	(version 20260206)
	(generator "pcbnew")
	(generator_version "10.0")
	(general
		(thickness 1.6)
		(legacy_teardrops no)
	)
	(paper "A4")
	(title_block
		(title "Wiwynn_Tioga_Pass_MB.brd")
		(comment 1 "Tioga Pass / footprint 2141 of 4770 (J1G2), pads 152-201 of 291")
	)
	(layers
		(0 "F.Cu" signal "TOP")
		(4 "In1.Cu" signal "L2GND")
		(6 "In2.Cu" signal "L3")
		(8 "In3.Cu" signal "L4GND")
		(10 "In4.Cu" signal "L5")
		(12 "In5.Cu" signal "L6GND")
		(14 "In6.Cu" signal "L7VCC")
		(16 "In7.Cu" signal "L8VCC")
		(18 "In8.Cu" signal "L9GND")
		(20 "In9.Cu" signal "L10")
		(22 "In10.Cu" signal "L11GND")
		(24 "In11.Cu" signal "L12")
		(26 "In12.Cu" signal "L13GND")
		(2 "B.Cu" signal "BOTTOM")
		(9 "F.Adhes" user "F.Adhesive")
		(11 "B.Adhes" user "B.Adhesive")
		(13 "F.Paste" user "Package Geometry/Pastemask Top")
		(15 "B.Paste" user "Package Geometry/Pastemask Bottom")
		(5 "F.SilkS" user "Ref Des/Silkscreen Top")
		(7 "B.SilkS" user "Ref Des/Silkscreen Bottom")
		(1 "F.Mask" user "Board Geometry/Soldermask Top")
		(3 "B.Mask" user "Board Geometry/Soldermask Bottom")
		(17 "Dwgs.User" user "User.Drawings")
		(19 "Cmts.User" user "User.Comments")
		(21 "Eco1.User" user "User.Eco1")
		(23 "Eco2.User" user "User.Eco2")
		(25 "Edge.Cuts" user "Board Geometry/Outline")
		(27 "Margin" user)
		(31 "F.CrtYd" user "Package Geometry/Place Bound Top")
		(29 "B.CrtYd" user "Package Geometry/Place Bound Bottom")
		(35 "F.Fab" user "Ref Des/Assembly Top")
		(33 "B.Fab" user "Ref Des/Assembly Bottom")
	)
	(footprint ""
		(layer "F.Cu")
		(at 29.699458 -5.822442 90)
		(property "Reference" "J1G2"
			(at 7.104888 34.562542 0)
			(unlocked yes)
			(layer "F.SilkS")
			(effects
				(font
					(size 0.7874 0.5842)
					(thickness 0.1524)
				)
				(justify left)
			)
		)
		(property "Value" ""
			(at 0 0 90)
			(layer "F.Fab")
			(effects
				(font
					(size 1.27 1.27)
				)
			)
		)
		(duplicate_pad_numbers_are_jumpers no)
		(pad "149" smd rect
			(at 4.59994 3.400044 90)
			(size 1.8034 0.508)
			(layers "F.Cu" "F.Mask" "F.Paste")
			(net "GND")
		)
		(pad "150" smd rect
			(at 4.59994 4.249928 90)
			(size 1.8034 0.508)
			(layers "F.Cu" "F.Mask" "F.Paste")
			(net "M_H_DQ<0>")
		)
		(pad "151" smd rect
			(at 4.59994 5.100066 90)
			(size 1.8034 0.508)
			(layers "F.Cu" "F.Mask" "F.Paste")
			(net "GND")
		)
		(pad "152" smd rect
			(at 4.59994 5.94995 90)
			(size 1.8034 0.508)
			(layers "F.Cu" "F.Mask" "F.Paste")
			(net "M_H_DQS_DN<0>")
		)
		(pad "153" smd rect
			(at 4.59994 6.800088 90)
			(size 1.8034 0.508)
			(layers "F.Cu" "F.Mask" "F.Paste")
			(net "M_H_DQS_DP<0>")
		)
		(pad "154" smd rect
			(at 4.59994 7.649972 90)
			(size 1.8034 0.508)
			(layers "F.Cu" "F.Mask" "F.Paste")
			(net "GND")
		)
		(pad "155" smd rect
			(at 4.59994 8.50011 90)
			(size 1.8034 0.508)
			(layers "F.Cu" "F.Mask" "F.Paste")
			(net "M_H_DQ<6>")
		)
		(pad "156" smd rect
			(at 4.59994 9.349994 90)
			(size 1.8034 0.508)
			(layers "F.Cu" "F.Mask" "F.Paste")
			(net "GND")
		)
		(pad "157" smd rect
			(at 4.59994 10.199878 90)
			(size 1.8034 0.508)
			(layers "F.Cu" "F.Mask" "F.Paste")
			(net "M_H_DQ<2>")
		)
		(pad "158" smd rect
			(at 4.59994 11.050016 90)
			(size 1.8034 0.508)
			(layers "F.Cu" "F.Mask" "F.Paste")
			(net "GND")
		)
		(pad "159" smd rect
			(at 4.59994 11.8999 90)
			(size 1.8034 0.508)
			(layers "F.Cu" "F.Mask" "F.Paste")
			(net "M_H_DQ<12>")
		)
		(pad "160" smd rect
			(at 4.59994 12.750038 90)
			(size 1.8034 0.508)
			(layers "F.Cu" "F.Mask" "F.Paste")
			(net "GND")
		)
		(pad "161" smd rect
			(at 4.59994 13.599922 90)
			(size 1.8034 0.508)
			(layers "F.Cu" "F.Mask" "F.Paste")
			(net "M_H_DQ<8>")
		)
		(pad "162" smd rect
			(at 4.59994 14.45006 90)
			(size 1.8034 0.508)
			(layers "F.Cu" "F.Mask" "F.Paste")
			(net "GND")
		)
		(pad "163" smd rect
			(at 4.59994 15.299944 90)
			(size 1.8034 0.508)
			(layers "F.Cu" "F.Mask" "F.Paste")
			(net "M_H_DQS_DN<1>")
		)
		(pad "164" smd rect
			(at 4.59994 16.150082 90)
			(size 1.8034 0.508)
			(layers "F.Cu" "F.Mask" "F.Paste")
			(net "M_H_DQS_DP<1>")
		)
		(pad "165" smd rect
			(at 4.59994 16.999966 90)
			(size 1.8034 0.508)
			(layers "F.Cu" "F.Mask" "F.Paste")
			(net "GND")
		)
		(pad "166" smd rect
			(at 4.59994 17.850104 90)
			(size 1.8034 0.508)
			(layers "F.Cu" "F.Mask" "F.Paste")
			(net "M_H_DQ<14>")
		)
		(pad "167" smd rect
			(at 4.59994 18.699988 90)
			(size 1.8034 0.508)
			(layers "F.Cu" "F.Mask" "F.Paste")
			(net "GND")
		)
		(pad "168" smd rect
			(at 4.59994 19.550126 90)
			(size 1.8034 0.508)
			(layers "F.Cu" "F.Mask" "F.Paste")
			(net "M_H_DQ<10>")
		)
		(pad "169" smd rect
			(at 4.59994 20.40001 90)
			(size 1.8034 0.508)
			(layers "F.Cu" "F.Mask" "F.Paste")
			(net "GND")
		)
		(pad "170" smd rect
			(at 4.59994 21.249894 90)
			(size 1.8034 0.508)
			(layers "F.Cu" "F.Mask" "F.Paste")
			(net "M_H_DQ<20>")
		)
		(pad "171" smd rect
			(at 4.59994 22.100032 90)
			(size 1.8034 0.508)
			(layers "F.Cu" "F.Mask" "F.Paste")
			(net "GND")
		)
		(pad "172" smd rect
			(at 4.59994 22.949916 90)
			(size 1.8034 0.508)
			(layers "F.Cu" "F.Mask" "F.Paste")
			(net "M_H_DQ<16>")
		)
		(pad "173" smd rect
			(at 4.59994 23.800054 90)
			(size 1.8034 0.508)
			(layers "F.Cu" "F.Mask" "F.Paste")
			(net "GND")
		)
		(pad "174" smd rect
			(at 4.59994 24.649938 90)
			(size 1.8034 0.508)
			(layers "F.Cu" "F.Mask" "F.Paste")
			(net "M_H_DQS_DN<2>")
		)
		(pad "175" smd rect
			(at 4.59994 25.500076 90)
			(size 1.8034 0.508)
			(layers "F.Cu" "F.Mask" "F.Paste")
			(net "M_H_DQS_DP<2>")
		)
		(pad "176" smd rect
			(at 4.59994 26.34996 90)
			(size 1.8034 0.508)
			(layers "F.Cu" "F.Mask" "F.Paste")
			(net "GND")
		)
		(pad "177" smd rect
			(at 4.59994 27.200098 90)
			(size 1.8034 0.508)
			(layers "F.Cu" "F.Mask" "F.Paste")
			(net "M_H_DQ<22>")
		)
		(pad "178" smd rect
			(at 4.59994 28.049982 90)
			(size 1.8034 0.508)
			(layers "F.Cu" "F.Mask" "F.Paste")
			(net "GND")
		)
		(pad "179" smd rect
			(at 4.59994 28.90012 90)
			(size 1.8034 0.508)
			(layers "F.Cu" "F.Mask" "F.Paste")
			(net "M_H_DQ<18>")
		)
		(pad "180" smd rect
			(at 4.59994 29.750004 90)
			(size 1.8034 0.508)
			(layers "F.Cu" "F.Mask" "F.Paste")
			(net "GND")
		)
		(pad "181" smd rect
			(at 4.59994 30.599888 90)
			(size 1.8034 0.508)
			(layers "F.Cu" "F.Mask" "F.Paste")
			(net "M_H_DQ<28>")
		)
		(pad "182" smd rect
			(at 4.59994 31.450026 90)
			(size 1.8034 0.508)
			(layers "F.Cu" "F.Mask" "F.Paste")
			(net "GND")
		)
		(pad "183" smd rect
			(at 4.59994 32.29991 90)
			(size 1.8034 0.508)
			(layers "F.Cu" "F.Mask" "F.Paste")
			(net "M_H_DQ<24>")
		)
		(pad "184" smd rect
			(at 4.59994 33.150048 90)
			(size 1.8034 0.508)
			(layers "F.Cu" "F.Mask" "F.Paste")
			(net "GND")
		)
		(pad "185" smd rect
			(at 4.59994 33.999932 90)
			(size 1.8034 0.508)
			(layers "F.Cu" "F.Mask" "F.Paste")
			(net "M_H_DQS_DN<3>")
		)
		(pad "186" smd rect
			(at 4.59994 34.85007 90)
			(size 1.8034 0.508)
			(layers "F.Cu" "F.Mask" "F.Paste")
			(net "M_H_DQS_DP<3>")
		)
		(pad "187" smd rect
			(at 4.59994 35.699954 90)
			(size 1.8034 0.508)
			(layers "F.Cu" "F.Mask" "F.Paste")
			(net "GND")
		)
		(pad "188" smd rect
			(at 4.59994 36.550092 90)
			(size 1.8034 0.508)
			(layers "F.Cu" "F.Mask" "F.Paste")
			(net "M_H_DQ<30>")
		)
		(pad "189" smd rect
			(at 4.59994 37.399976 90)
			(size 1.8034 0.508)
			(layers "F.Cu" "F.Mask" "F.Paste")
			(net "GND")
		)
		(pad "190" smd rect
			(at 4.59994 38.250114 90)
			(size 1.8034 0.508)
			(layers "F.Cu" "F.Mask" "F.Paste")
			(net "M_H_DQ<26>")
		)
		(pad "191" smd rect
			(at 4.59994 39.099998 90)
			(size 1.8034 0.508)
			(layers "F.Cu" "F.Mask" "F.Paste")
			(net "GND")
		)
		(pad "192" smd rect
			(at 4.59994 39.949882 90)
			(size 1.8034 0.508)
			(layers "F.Cu" "F.Mask" "F.Paste")
			(net "M_H_ECC<4>")
		)
		(pad "193" smd rect
			(at 4.59994 40.80002 90)
			(size 1.8034 0.508)
			(layers "F.Cu" "F.Mask" "F.Paste")
			(net "GND")
		)
		(pad "194" smd rect
			(at 4.59994 41.649904 90)
			(size 1.8034 0.508)
			(layers "F.Cu" "F.Mask" "F.Paste")
			(net "M_H_ECC<0>")
		)
		(pad "195" smd rect
			(at 4.59994 42.500042 90)
			(size 1.8034 0.508)
			(layers "F.Cu" "F.Mask" "F.Paste")
			(net "GND")
		)
		(pad "196" smd rect
			(at 4.59994 43.349926 90)
			(size 1.8034 0.508)
			(layers "F.Cu" "F.Mask" "F.Paste")
			(net "M_H_DQS_DN<8>")
		)
		(pad "197" smd rect
			(at 4.59994 44.200064 90)
			(size 1.8034 0.508)
			(layers "F.Cu" "F.Mask" "F.Paste")
			(net "M_H_DQS_DP<8>")
		)
		(pad "198" smd rect
			(at 4.59994 45.049948 90)
			(size 1.8034 0.508)
			(layers "F.Cu" "F.Mask" "F.Paste")
			(net "GND")
		)
	)
)
